(kicad_pcb
	(version 20260206)
	(generator "pcbnew")
	(generator_version "10.0")
	(general
		(thickness 1.6)
		(legacy_teardrops no)
	)
	(paper "A4")
	(title_block
		(title "baseboard — 13948-1b.1110WZS1818.brd")
		(comment 1 "Honey Badger (Wiwynn) / footprint 852 of 2523 (SU2), pads 731-854 of 896")
	)
	(layers
		(0 "F.Cu" signal "TOP")
		(4 "In1.Cu" signal "L2GND")
		(6 "In2.Cu" signal "L3")
		(8 "In3.Cu" signal "L4VCC")
		(10 "In4.Cu" signal "L5VCC")
		(12 "In5.Cu" signal "L6")
		(14 "In6.Cu" signal "L7GND")
		(2 "B.Cu" signal "BOTTOM")
		(9 "F.Adhes" user "F.Adhesive")
		(11 "B.Adhes" user "B.Adhesive")
		(13 "F.Paste" user "Package Geometry/Pastemask Top")
		(15 "B.Paste" user "Package Geometry/Pastemask Bottom")
		(5 "F.SilkS" user "Ref Des/Silkscreen Top")
		(7 "B.SilkS" user "Ref Des/Silkscreen Bottom")
		(1 "F.Mask" user "Board Geometry/Soldermask Top")
		(3 "B.Mask" user "Board Geometry/Soldermask Bottom")
		(17 "Dwgs.User" user "User.Drawings")
		(19 "Cmts.User" user "User.Comments")
		(21 "Eco1.User" user "User.Eco1")
		(23 "Eco2.User" user "User.Eco2")
		(25 "Edge.Cuts" user "Board Geometry/Outline")
		(27 "Margin" user)
		(31 "F.CrtYd" user "Package Geometry/Place Bound Top")
		(29 "B.CrtYd" user "Package Geometry/Place Bound Bottom")
		(35 "F.Fab" user "Ref Des/Assembly Top")
		(33 "B.Fab" user "Ref Des/Assembly Bottom")
	)
	(footprint ""
		(layer "F.Cu")
		(at 102.350062 -44.99991)
		(property "Reference" "SU2"
			(at 0 0 0)
			(layer "F.SilkS")
			(hide yes)
			(effects
				(font
					(size 1.27 1.27)
				)
			)
		)
		(property "Value" "SAS3008C0-1-DB-500020657-1-GP"
			(at -20.374102 -5.0292 0)
			(unlocked yes)
			(layer "F.Fab")
			(hide yes)
			(effects
				(font
					(size 1.016 1.016)
					(thickness 0.1524)
				)
			)
		)
		(property "Device Type" "BGA896D25H78"
			(at -20.374102 -6.5532 0)
			(unlocked yes)
			(layer "F.Fab")
			(hide yes)
			(effects
				(font
					(size 1.016 1.016)
					(thickness 0.1524)
				)
			)
		)
		(duplicate_pad_numbers_are_jumpers no)
		(pad "R15" smd circle
			(at -0.40005 -0.40005)
			(size 0.3556 0.3556)
			(layers "F.Cu" "F.Mask" "F.Paste")
			(net "GND")
		)
		(pad "R16" smd circle
			(at 0.40005 -0.40005)
			(size 0.3556 0.3556)
			(layers "F.Cu" "F.Mask" "F.Paste")
			(net "P0V955_C")
		)
		(pad "R17" smd circle
			(at 1.199896 -0.40005)
			(size 0.3556 0.3556)
			(layers "F.Cu" "F.Mask" "F.Paste")
			(net "GND")
		)
		(pad "R18" smd circle
			(at 1.999996 -0.40005)
			(size 0.3556 0.3556)
			(layers "F.Cu" "F.Mask" "F.Paste")
			(net "P0V955_C")
		)
		(pad "R19" smd circle
			(at 2.800096 -0.40005)
			(size 0.3556 0.3556)
			(layers "F.Cu" "F.Mask" "F.Paste")
			(net "GND")
		)
		(pad "R20" smd circle
			(at 3.599942 -0.40005)
			(size 0.3556 0.3556)
			(layers "F.Cu" "F.Mask" "F.Paste")
			(net "P0V955_C")
		)
		(pad "R21" smd circle
			(at 4.400042 -0.40005)
			(size 0.3556 0.3556)
			(layers "F.Cu" "F.Mask" "F.Paste")
			(net "GND")
		)
		(pad "R22" smd circle
			(at 5.199888 -0.40005)
			(size 0.3556 0.3556)
			(layers "F.Cu" "F.Mask" "F.Paste")
			(net "GND")
		)
		(pad "R23" smd circle
			(at 5.999988 -0.40005)
			(size 0.3556 0.3556)
			(layers "F.Cu" "F.Mask" "F.Paste")
			(net "GND")
		)
		(pad "R24" smd circle
			(at 6.800088 -0.40005)
			(size 0.3556 0.3556)
			(layers "F.Cu" "F.Mask" "F.Paste")
			(net "GND")
		)
		(pad "R25" smd circle
			(at 7.599934 -0.40005)
			(size 0.3556 0.3556)
			(layers "F.Cu" "F.Mask" "F.Paste")
			(net "GND")
		)
		(pad "R26" smd circle
			(at 8.400034 -0.40005)
			(size 0.3556 0.3556)
			(layers "F.Cu" "F.Mask" "F.Paste")
			(net "GND")
		)
		(pad "R27" smd circle
			(at 9.19988 -0.40005)
			(size 0.3556 0.3556)
			(layers "F.Cu" "F.Mask" "F.Paste")
			(net "P1V8_C")
		)
		(pad "R28" smd circle
			(at 9.99998 -0.40005)
			(size 0.3556 0.3556)
			(layers "F.Cu" "F.Mask" "F.Paste")
			(net "IOC_SDA_4")
		)
		(pad "R29" smd circle
			(at 10.80008 -0.40005)
			(size 0.3556 0.3556)
			(layers "F.Cu" "F.Mask" "F.Paste")
			(net "IOC_SDA_0")
		)
		(pad "R30" smd circle
			(at 11.599926 -0.40005)
			(size 0.3556 0.3556)
			(layers "F.Cu" "F.Mask" "F.Paste")
			(net "SYS_CORE_TRI#")
		)
		(pad "T1" smd circle
			(at -11.599926 0.40005)
			(size 0.3556 0.3556)
			(layers "F.Cu" "F.Mask" "F.Paste")
			(net "RTRIM")
		)
		(pad "T2" smd circle
			(at -10.80008 0.40005)
			(size 0.3556 0.3556)
			(layers "F.Cu" "F.Mask" "F.Paste")
			(net "RTRIM#")
		)
		(pad "T3" smd circle
			(at -9.99998 0.40005)
			(size 0.3556 0.3556)
			(layers "F.Cu" "F.Mask" "F.Paste")
			(net "GND")
		)
		(pad "T4" smd circle
			(at -9.19988 0.40005)
			(size 0.3556 0.3556)
			(layers "F.Cu" "F.Mask" "F.Paste")
			(net "OSC_REF_CLK")
		)
		(pad "T5" smd circle
			(at -8.400034 0.40005)
			(size 0.3556 0.3556)
			(layers "F.Cu" "F.Mask" "F.Paste")
			(net "GND")
		)
		(pad "T6" smd circle
			(at -7.599934 0.40005)
			(size 0.3556 0.3556)
			(layers "F.Cu" "F.Mask" "F.Paste")
			(net "SIO_DIN_0")
		)
		(pad "T7" smd circle
			(at -6.800088 0.40005)
			(size 0.3556 0.3556)
			(layers "F.Cu" "F.Mask" "F.Paste")
			(net "GND")
		)
		(pad "T8" smd circle
			(at -5.999988 0.40005)
			(size 0.3556 0.3556)
			(layers "F.Cu" "F.Mask" "F.Paste")
			(net "GND")
		)
		(pad "T9" smd circle
			(at -5.199888 0.40005)
			(size 0.3556 0.3556)
			(layers "F.Cu" "F.Mask" "F.Paste")
			(net "SYS_PLL_VDD")
		)
		(pad "T10" smd circle
			(at -4.400042 0.40005)
			(size 0.3556 0.3556)
			(layers "F.Cu" "F.Mask" "F.Paste")
			(net "GND")
		)
		(pad "T11" smd circle
			(at -3.599942 0.40005)
			(size 0.3556 0.3556)
			(layers "F.Cu" "F.Mask" "F.Paste")
			(net "GND")
		)
		(pad "T12" smd circle
			(at -2.800096 0.40005)
			(size 0.3556 0.3556)
			(layers "F.Cu" "F.Mask" "F.Paste")
			(net "GND")
		)
		(pad "T13" smd circle
			(at -1.999996 0.40005)
			(size 0.3556 0.3556)
			(layers "F.Cu" "F.Mask" "F.Paste")
			(net "P0V955_C")
		)
		(pad "T14" smd circle
			(at -1.199896 0.40005)
			(size 0.3556 0.3556)
			(layers "F.Cu" "F.Mask" "F.Paste")
			(net "GND")
		)
		(pad "T15" smd circle
			(at -0.40005 0.40005)
			(size 0.3556 0.3556)
			(layers "F.Cu" "F.Mask" "F.Paste")
			(net "P0V955_C")
		)
		(pad "T16" smd circle
			(at 0.40005 0.40005)
			(size 0.3556 0.3556)
			(layers "F.Cu" "F.Mask" "F.Paste")
			(net "GND")
		)
		(pad "T17" smd circle
			(at 1.199896 0.40005)
			(size 0.3556 0.3556)
			(layers "F.Cu" "F.Mask" "F.Paste")
			(net "P0V955_C")
		)
		(pad "T18" smd circle
			(at 1.999996 0.40005)
			(size 0.3556 0.3556)
			(layers "F.Cu" "F.Mask" "F.Paste")
			(net "GND")
		)
		(pad "T19" smd circle
			(at 2.800096 0.40005)
			(size 0.3556 0.3556)
			(layers "F.Cu" "F.Mask" "F.Paste")
			(net "P0V955_C")
		)
		(pad "T20" smd circle
			(at 3.599942 0.40005)
			(size 0.3556 0.3556)
			(layers "F.Cu" "F.Mask" "F.Paste")
			(net "GND")
		)
		(pad "T21" smd circle
			(at 4.400042 0.40005)
			(size 0.3556 0.3556)
			(layers "F.Cu" "F.Mask" "F.Paste")
			(net "P0V955_C")
		)
		(pad "T22" smd circle
			(at 5.199888 0.40005)
			(size 0.3556 0.3556)
			(layers "F.Cu" "F.Mask" "F.Paste")
			(net "GND")
		)
		(pad "T23" smd circle
			(at 5.999988 0.40005)
			(size 0.3556 0.3556)
			(layers "F.Cu" "F.Mask" "F.Paste")
			(net "GND")
		)
		(pad "T24" smd circle
			(at 6.800088 0.40005)
			(size 0.3556 0.3556)
			(layers "F.Cu" "F.Mask" "F.Paste")
			(net "GND")
		)
		(pad "T25" smd circle
			(at 7.599934 0.40005)
			(size 0.3556 0.3556)
			(layers "F.Cu" "F.Mask" "F.Paste")
			(net "GND")
		)
		(pad "T26" smd circle
			(at 8.400034 0.40005)
			(size 0.3556 0.3556)
			(layers "F.Cu" "F.Mask" "F.Paste")
			(net "P1V8_C")
		)
		(pad "T27" smd circle
			(at 9.19988 0.40005)
			(size 0.3556 0.3556)
			(layers "F.Cu" "F.Mask" "F.Paste")
			(net "GND")
		)
		(pad "T28" smd circle
			(at 9.99998 0.40005)
			(size 0.3556 0.3556)
			(layers "F.Cu" "F.Mask" "F.Paste")
			(net "IOC_CLK_SEL1")
		)
		(pad "T29" smd circle
			(at 10.80008 0.40005)
			(size 0.3556 0.3556)
			(layers "F.Cu" "F.Mask" "F.Paste")
			(net "SYS_HB_LED")
		)
		(pad "T30" smd circle
			(at 11.599926 0.40005)
			(size 0.3556 0.3556)
			(layers "F.Cu" "F.Mask" "F.Paste")
			(net "SBL_SCL")
		)
		(pad "U1" smd circle
			(at -11.599926 1.199896)
			(size 0.3556 0.3556)
			(layers "F.Cu" "F.Mask" "F.Paste")
			(net "SAS0_VDDH")
		)
		(pad "U2" smd circle
			(at -10.80008 1.199896)
			(size 0.3556 0.3556)
			(layers "F.Cu" "F.Mask" "F.Paste")
			(net "GND")
		)
		(pad "U3" smd circle
			(at -9.99998 1.199896)
			(size 0.3556 0.3556)
			(layers "F.Cu" "F.Mask" "F.Paste")
			(net "GND")
		)
		(pad "U4" smd circle
			(at -9.19988 1.199896)
			(size 0.3556 0.3556)
			(layers "F.Cu" "F.Mask" "F.Paste")
			(net "GND")
		)
		(pad "U5" smd circle
			(at -8.400034 1.199896)
			(size 0.3556 0.3556)
			(layers "F.Cu" "F.Mask" "F.Paste")
			(net "GND")
		)
		(pad "U6" smd circle
			(at -7.599934 1.199896)
			(size 0.3556 0.3556)
			(layers "F.Cu" "F.Mask" "F.Paste")
			(net "GND")
		)
		(pad "U7" smd circle
			(at -6.800088 1.199896)
			(size 0.3556 0.3556)
			(layers "F.Cu" "F.Mask" "F.Paste")
			(net "GND")
		)
		(pad "U8" smd circle
			(at -5.999988 1.199896)
			(size 0.3556 0.3556)
			(layers "F.Cu" "F.Mask" "F.Paste")
			(net "GND")
		)
		(pad "U9" smd circle
			(at -5.199888 1.199896)
			(size 0.3556 0.3556)
			(layers "F.Cu" "F.Mask" "F.Paste")
			(net "GND")
		)
		(pad "U10" smd circle
			(at -4.400042 1.199896)
			(size 0.3556 0.3556)
			(layers "F.Cu" "F.Mask" "F.Paste")
			(net "SHELL_PLL_VDD")
		)
		(pad "U11" smd circle
			(at -3.599942 1.199896)
			(size 0.3556 0.3556)
			(layers "F.Cu" "F.Mask" "F.Paste")
			(net "GND")
		)
		(pad "U12" smd circle
			(at -2.800096 1.199896)
			(size 0.3556 0.3556)
			(layers "F.Cu" "F.Mask" "F.Paste")
			(net "P0V955_C")
		)
		(pad "U13" smd circle
			(at -1.999996 1.199896)
			(size 0.3556 0.3556)
			(layers "F.Cu" "F.Mask" "F.Paste")
			(net "GND")
		)
		(pad "U14" smd circle
			(at -1.199896 1.199896)
			(size 0.3556 0.3556)
			(layers "F.Cu" "F.Mask" "F.Paste")
			(net "P0V955_C")
		)
		(pad "U15" smd circle
			(at -0.40005 1.199896)
			(size 0.3556 0.3556)
			(layers "F.Cu" "F.Mask" "F.Paste")
			(net "GND")
		)
		(pad "U16" smd circle
			(at 0.40005 1.199896)
			(size 0.3556 0.3556)
			(layers "F.Cu" "F.Mask" "F.Paste")
			(net "P0V955_C")
		)
		(pad "U17" smd circle
			(at 1.199896 1.199896)
			(size 0.3556 0.3556)
			(layers "F.Cu" "F.Mask" "F.Paste")
			(net "GND")
		)
		(pad "U18" smd circle
			(at 1.999996 1.199896)
			(size 0.3556 0.3556)
			(layers "F.Cu" "F.Mask" "F.Paste")
			(net "P0V955_C")
		)
		(pad "U19" smd circle
			(at 2.800096 1.199896)
			(size 0.3556 0.3556)
			(layers "F.Cu" "F.Mask" "F.Paste")
			(net "GND")
		)
		(pad "U20" smd circle
			(at 3.599942 1.199896)
			(size 0.3556 0.3556)
			(layers "F.Cu" "F.Mask" "F.Paste")
			(net "P0V955_C")
		)
		(pad "U21" smd circle
			(at 4.400042 1.199896)
			(size 0.3556 0.3556)
			(layers "F.Cu" "F.Mask" "F.Paste")
			(net "GND")
		)
		(pad "U22" smd circle
			(at 5.199888 1.199896)
			(size 0.3556 0.3556)
			(layers "F.Cu" "F.Mask" "F.Paste")
			(net "GND")
		)
		(pad "U23" smd circle
			(at 5.999988 1.199896)
			(size 0.3556 0.3556)
			(layers "F.Cu" "F.Mask" "F.Paste")
			(net "GND")
		)
		(pad "U24" smd circle
			(at 6.800088 1.199896)
			(size 0.3556 0.3556)
			(layers "F.Cu" "F.Mask" "F.Paste")
			(net "GND")
		)
		(pad "U25" smd circle
			(at 7.599934 1.199896)
			(size 0.3556 0.3556)
			(layers "F.Cu" "F.Mask" "F.Paste")
			(net "GND")
		)
		(pad "U26" smd circle
			(at 8.400034 1.199896)
			(size 0.3556 0.3556)
			(layers "F.Cu" "F.Mask" "F.Paste")
			(net "GND")
		)
		(pad "U27" smd circle
			(at 9.19988 1.199896)
			(size 0.3556 0.3556)
			(layers "F.Cu" "F.Mask" "F.Paste")
			(net "P1V8_C")
		)
		(pad "U28" smd circle
			(at 9.99998 1.199896)
			(size 0.3556 0.3556)
			(layers "F.Cu" "F.Mask" "F.Paste")
			(net "IOC_RESET#")
		)
		(pad "U29" smd circle
			(at 10.80008 1.199896)
			(size 0.3556 0.3556)
			(layers "F.Cu" "F.Mask" "F.Paste")
			(net "IOC_SDA_3")
		)
		(pad "U30" smd circle
			(at 11.599926 1.199896)
			(size 0.3556 0.3556)
			(layers "F.Cu" "F.Mask" "F.Paste")
			(net "CP_DONE")
		)
		(pad "V1" smd circle
			(at -11.599926 1.999996)
			(size 0.3556 0.3556)
			(layers "F.Cu" "F.Mask" "F.Paste")
			(net "SAS3008_RAID_TX_C_P4")
		)
		(pad "V2" smd circle
			(at -10.80008 1.999996)
			(size 0.3556 0.3556)
			(layers "F.Cu" "F.Mask" "F.Paste")
			(net "SAS3008_RAID_TX_C_N4")
		)
		(pad "V3" smd circle
			(at -9.99998 1.999996)
			(size 0.3556 0.3556)
			(layers "F.Cu" "F.Mask" "F.Paste")
			(net "GND")
		)
		(pad "V4" smd circle
			(at -9.19988 1.999996)
			(size 0.3556 0.3556)
			(layers "F.Cu" "F.Mask" "F.Paste")
			(net "IOC_SAS_RX_P4")
		)
		(pad "V5" smd circle
			(at -8.400034 1.999996)
			(size 0.3556 0.3556)
			(layers "F.Cu" "F.Mask" "F.Paste")
			(net "IOC_SAS_RX_N4")
		)
		(pad "V6" smd circle
			(at -7.599934 1.999996)
			(size 0.3556 0.3556)
			(layers "F.Cu" "F.Mask" "F.Paste")
			(net "GND")
		)
		(pad "V7" smd circle
			(at -6.800088 1.999996)
			(size 0.3556 0.3556)
			(layers "F.Cu" "F.Mask" "F.Paste")
			(net "SAS0_AVDD")
		)
		(pad "V8" smd circle
			(at -5.999988 1.999996)
			(size 0.3556 0.3556)
			(layers "F.Cu" "F.Mask" "F.Paste")
			(net "GND")
		)
		(pad "V9" smd circle
			(at -5.199888 1.999996)
			(size 0.3556 0.3556)
			(layers "F.Cu" "F.Mask" "F.Paste")
			(net "SAS0_AVDD")
		)
		(pad "V10" smd circle
			(at -4.400042 1.999996)
			(size 0.3556 0.3556)
			(layers "F.Cu" "F.Mask" "F.Paste")
			(net "GND")
		)
		(pad "V11" smd circle
			(at -3.599942 1.999996)
			(size 0.3556 0.3556)
			(layers "F.Cu" "F.Mask" "F.Paste")
			(net "VDDA_SAS_REF_CLK")
		)
		(pad "V12" smd circle
			(at -2.800096 1.999996)
			(size 0.3556 0.3556)
			(layers "F.Cu" "F.Mask" "F.Paste")
			(net "GND")
		)
		(pad "V13" smd circle
			(at -1.999996 1.999996)
			(size 0.3556 0.3556)
			(layers "F.Cu" "F.Mask" "F.Paste")
			(net "P0V955_C")
		)
		(pad "V14" smd circle
			(at -1.199896 1.999996)
			(size 0.3556 0.3556)
			(layers "F.Cu" "F.Mask" "F.Paste")
			(net "GND")
		)
		(pad "V15" smd circle
			(at -0.40005 1.999996)
			(size 0.3556 0.3556)
			(layers "F.Cu" "F.Mask" "F.Paste")
			(net "P0V955_C")
		)
		(pad "V16" smd circle
			(at 0.40005 1.999996)
			(size 0.3556 0.3556)
			(layers "F.Cu" "F.Mask" "F.Paste")
			(net "GND")
		)
		(pad "V17" smd circle
			(at 1.199896 1.999996)
			(size 0.3556 0.3556)
			(layers "F.Cu" "F.Mask" "F.Paste")
			(net "P0V955_C")
		)
		(pad "V18" smd circle
			(at 1.999996 1.999996)
			(size 0.3556 0.3556)
			(layers "F.Cu" "F.Mask" "F.Paste")
			(net "GND")
		)
		(pad "V19" smd circle
			(at 2.800096 1.999996)
			(size 0.3556 0.3556)
			(layers "F.Cu" "F.Mask" "F.Paste")
			(net "P0V955_C")
		)
		(pad "V20" smd circle
			(at 3.599942 1.999996)
			(size 0.3556 0.3556)
			(layers "F.Cu" "F.Mask" "F.Paste")
			(net "GND")
		)
		(pad "V21" smd circle
			(at 4.400042 1.999996)
			(size 0.3556 0.3556)
			(layers "F.Cu" "F.Mask" "F.Paste")
			(net "P0V955_C")
		)
		(pad "V22" smd circle
			(at 5.199888 1.999996)
			(size 0.3556 0.3556)
			(layers "F.Cu" "F.Mask" "F.Paste")
			(net "GND")
		)
		(pad "V23" smd circle
			(at 5.999988 1.999996)
			(size 0.3556 0.3556)
			(layers "F.Cu" "F.Mask" "F.Paste")
			(net "GND")
		)
		(pad "V24" smd circle
			(at 6.800088 1.999996)
			(size 0.3556 0.3556)
			(layers "F.Cu" "F.Mask" "F.Paste")
			(net "GND")
		)
		(pad "V25" smd circle
			(at 7.599934 1.999996)
			(size 0.3556 0.3556)
			(layers "F.Cu" "F.Mask" "F.Paste")
			(net "GND")
		)
		(pad "V26" smd circle
			(at 8.400034 1.999996)
			(size 0.3556 0.3556)
			(layers "F.Cu" "F.Mask" "F.Paste")
			(net "P1V8_C")
		)
		(pad "V27" smd circle
			(at 9.19988 1.999996)
			(size 0.3556 0.3556)
			(layers "F.Cu" "F.Mask" "F.Paste")
			(net "GND")
		)
		(pad "V28" smd circle
			(at 9.99998 1.999996)
			(size 0.3556 0.3556)
			(layers "F.Cu" "F.Mask" "F.Paste")
			(net "IOC_SCL_2")
		)
		(pad "V29" smd circle
			(at 10.80008 1.999996)
			(size 0.3556 0.3556)
			(layers "F.Cu" "F.Mask" "F.Paste")
			(net "IOC_SCL_0")
		)
		(pad "V30" smd circle
			(at 11.599926 1.999996)
			(size 0.3556 0.3556)
			(layers "F.Cu" "F.Mask" "F.Paste")
			(net "IOC_SDA_1")
		)
		(pad "W1" smd circle
			(at -11.599926 2.800096)
			(size 0.3556 0.3556)
			(layers "F.Cu" "F.Mask" "F.Paste")
			(net "SAS3008_RAID_TX_C_P5")
		)
		(pad "W2" smd circle
			(at -10.80008 2.800096)
			(size 0.3556 0.3556)
			(layers "F.Cu" "F.Mask" "F.Paste")
			(net "SAS3008_RAID_TX_C_N5")
		)
		(pad "W3" smd circle
			(at -9.99998 2.800096)
			(size 0.3556 0.3556)
			(layers "F.Cu" "F.Mask" "F.Paste")
			(net "GND")
		)
		(pad "W4" smd circle
			(at -9.19988 2.800096)
			(size 0.3556 0.3556)
			(layers "F.Cu" "F.Mask" "F.Paste")
			(net "IOC_SAS_RX_P5")
		)
		(pad "W5" smd circle
			(at -8.400034 2.800096)
			(size 0.3556 0.3556)
			(layers "F.Cu" "F.Mask" "F.Paste")
			(net "IOC_SAS_RX_N5")
		)
		(pad "W6" smd circle
			(at -7.599934 2.800096)
			(size 0.3556 0.3556)
			(layers "F.Cu" "F.Mask" "F.Paste")
			(net "GND")
		)
		(pad "W7" smd circle
			(at -6.800088 2.800096)
			(size 0.3556 0.3556)
			(layers "F.Cu" "F.Mask" "F.Paste")
			(net "GND")
		)
		(pad "W8" smd circle
			(at -5.999988 2.800096)
			(size 0.3556 0.3556)
			(layers "F.Cu" "F.Mask" "F.Paste")
			(net "GND")
		)
		(pad "W9" smd circle
			(at -5.199888 2.800096)
			(size 0.3556 0.3556)
			(layers "F.Cu" "F.Mask" "F.Paste")
			(net "GND")
		)
		(pad "W10" smd circle
			(at -4.400042 2.800096)
			(size 0.3556 0.3556)
			(layers "F.Cu" "F.Mask" "F.Paste")
			(net "GND")
		)
		(pad "W11" smd circle
			(at -3.599942 2.800096)
			(size 0.3556 0.3556)
			(layers "F.Cu" "F.Mask" "F.Paste")
			(net "GND")
		)
		(pad "W12" smd circle
			(at -2.800096 2.800096)
			(size 0.3556 0.3556)
			(layers "F.Cu" "F.Mask" "F.Paste")
			(net "GND")
		)
		(pad "W13" smd circle
			(at -1.999996 2.800096)
			(size 0.3556 0.3556)
			(layers "F.Cu" "F.Mask" "F.Paste")
			(net "GND")
		)
		(pad "W14" smd circle
			(at -1.199896 2.800096)
			(size 0.3556 0.3556)
			(layers "F.Cu" "F.Mask" "F.Paste")
			(net "P0V955_C")
		)
		(pad "W15" smd circle
			(at -0.40005 2.800096)
			(size 0.3556 0.3556)
			(layers "F.Cu" "F.Mask" "F.Paste")
			(net "GND")
		)
		(pad "W16" smd circle
			(at 0.40005 2.800096)
			(size 0.3556 0.3556)
			(layers "F.Cu" "F.Mask" "F.Paste")
			(net "P0V955_C")
		)
		(pad "W17" smd circle
			(at 1.199896 2.800096)
			(size 0.3556 0.3556)
			(layers "F.Cu" "F.Mask" "F.Paste")
			(net "GND")
		)
		(pad "W18" smd circle
			(at 1.999996 2.800096)
			(size 0.3556 0.3556)
			(layers "F.Cu" "F.Mask" "F.Paste")
			(net "P0V955_C")
		)
	)
)
